(kicad_pcb
	(version 20260206)
	(generator "pcbnew")
	(generator_version "10.0")
	(general
		(thickness 1.6)
		(legacy_teardrops no)
	)
	(paper "A4")
	(title_block
		(title "01162023_DA0F0TEBIF0_F0T_Expander_BD_F_brd_V02_OCP.brd")
		(comment 1 "Grand Teton / footprints 3587-3594 of 9728")
	)
	(layers
		(0 "F.Cu" signal "TOP")
		(4 "In1.Cu" signal "GND")
		(6 "In2.Cu" signal "VCC")
		(8 "In3.Cu" signal "VCC1")
		(10 "In4.Cu" signal "GND1")
		(12 "In5.Cu" signal "IN1")
		(14 "In6.Cu" signal "GND2")
		(16 "In7.Cu" signal "IN2")
		(18 "In8.Cu" signal "GND3")
		(20 "In9.Cu" signal "IN3")
		(22 "In10.Cu" signal "GND4")
		(24 "In11.Cu" signal "IN4")
		(26 "In12.Cu" signal "GND5")
		(28 "In13.Cu" signal "IN5")
		(30 "In14.Cu" signal "GND6")
		(32 "In15.Cu" signal "IN6")
		(34 "In16.Cu" signal "GND7")
		(2 "B.Cu" signal "BOTTOM")
		(9 "F.Adhes" user "F.Adhesive")
		(11 "B.Adhes" user "B.Adhesive")
		(13 "F.Paste" user "Package Geometry/Pastemask Top")
		(15 "B.Paste" user "Package Geometry/Pastemask Bottom")
		(5 "F.SilkS" user "Ref Des/Silkscreen Top")
		(7 "B.SilkS" user "Ref Des/Silkscreen Bottom")
		(1 "F.Mask" user "Board Geometry/Soldermask Top")
		(3 "B.Mask" user "Board Geometry/Soldermask Bottom")
		(17 "Dwgs.User" user "User.Drawings")
		(19 "Cmts.User" user "User.Comments")
		(21 "Eco1.User" user "User.Eco1")
		(23 "Eco2.User" user "User.Eco2")
		(25 "Edge.Cuts" user "Board Geometry/Outline")
		(27 "Margin" user)
		(31 "F.CrtYd" user "Package Geometry/Place Bound Top")
		(29 "B.CrtYd" user "Package Geometry/Place Bound Bottom")
		(35 "F.Fab" user "Ref Des/Assembly Top")
		(33 "B.Fab" user "Ref Des/Assembly Bottom")
	)
	(footprint ""
		(layer "F.Cu")
		(at 383.59842 -356.244906 90)
		(property "Reference" "C774"
			(at 0 0 90)
			(layer "F.SilkS")
			(hide yes)
			(effects
				(font
					(size 1.27 1.27)
				)
			)
		)
		(property "Value" ""
			(at 0 0 90)
			(layer "F.Fab")
			(effects
				(font
					(size 1.27 1.27)
				)
			)
		)
		(duplicate_pad_numbers_are_jumpers no)
		(fp_line
			(start 0.299974 -0.150114)
			(end 0.299974 0.150114)
			(stroke
				(width 0.1)
				(type default)
			)
			(layer "F.Fab")
		)
		(fp_line
			(start -0.299974 -0.150114)
			(end 0.299974 -0.150114)
			(stroke
				(width 0.1)
				(type default)
			)
			(layer "F.Fab")
		)
		(fp_line
			(start 0.299974 0.150114)
			(end -0.299974 0.150114)
			(stroke
				(width 0.1)
				(type default)
			)
			(layer "F.Fab")
		)
		(fp_line
			(start -0.299974 0.150114)
			(end -0.299974 -0.150114)
			(stroke
				(width 0.1)
				(type default)
			)
			(layer "F.Fab")
		)
		(pad "1" smd rect
			(at -0.2667 0 90)
			(size 0.3048 0.381)
			(layers "F.Cu" "F.Mask" "F.Paste")
			(net "P5E_PEX3_STN6_TX_DP<105>")
		)
		(pad "2" smd rect
			(at 0.2667 0 90)
			(size 0.3048 0.381)
			(layers "F.Cu" "F.Mask" "F.Paste")
			(net "P5E_PEX3_STN6_TX_C_DP<105>")
		)
	)
	(footprint ""
		(layer "F.Cu")
		(at 299.90161 -198.238872 90)
		(property "Reference" "C2108"
			(at 0 0 90)
			(layer "F.SilkS")
			(hide yes)
			(effects
				(font
					(size 1.27 1.27)
				)
			)
		)
		(property "Value" ""
			(at 0 0 90)
			(layer "F.Fab")
			(effects
				(font
					(size 1.27 1.27)
				)
			)
		)
		(duplicate_pad_numbers_are_jumpers no)
		(fp_line
			(start 0.7874 -0.4064)
			(end 0.7874 0.4064)
			(stroke
				(width 0.1524)
				(type default)
			)
			(layer "F.SilkS")
		)
		(fp_line
			(start -0.7874 -0.4064)
			(end 0.7874 -0.4064)
			(stroke
				(width 0.1524)
				(type default)
			)
			(layer "F.SilkS")
		)
		(fp_line
			(start 0.7874 0.4064)
			(end -0.7874 0.4064)
			(stroke
				(width 0.1524)
				(type default)
			)
			(layer "F.SilkS")
		)
		(fp_line
			(start -0.7874 0.4064)
			(end -0.7874 -0.4064)
			(stroke
				(width 0.1524)
				(type default)
			)
			(layer "F.SilkS")
		)
		(fp_line
			(start -0.12065 -0.305054)
			(end -0.12065 -0.2794)
			(stroke
				(width 0.1)
				(type default)
			)
			(layer "F.Fab")
		)
		(fp_line
			(start -0.67945 -0.305054)
			(end -0.12065 -0.305054)
			(stroke
				(width 0.1)
				(type default)
			)
			(layer "F.Fab")
		)
		(fp_line
			(start 0.67945 -0.3048)
			(end 0.67945 0.3048)
			(stroke
				(width 0.1)
				(type default)
			)
			(layer "F.Fab")
		)
		(fp_line
			(start 0.12065 -0.3048)
			(end 0.67945 -0.3048)
			(stroke
				(width 0.1)
				(type default)
			)
			(layer "F.Fab")
		)
		(fp_line
			(start 0.12065 -0.2794)
			(end 0.12065 -0.3048)
			(stroke
				(width 0.1)
				(type default)
			)
			(layer "F.Fab")
		)
		(fp_line
			(start -0.12065 -0.2794)
			(end 0.12065 -0.2794)
			(stroke
				(width 0.1)
				(type default)
			)
			(layer "F.Fab")
		)
		(fp_line
			(start 0.120396 0.2794)
			(end -0.12065 0.2794)
			(stroke
				(width 0.1)
				(type default)
			)
			(layer "F.Fab")
		)
		(fp_line
			(start -0.12065 0.2794)
			(end -0.12065 0.3048)
			(stroke
				(width 0.1)
				(type default)
			)
			(layer "F.Fab")
		)
		(fp_line
			(start 0.67945 0.3048)
			(end 0.120396 0.3048)
			(stroke
				(width 0.1)
				(type default)
			)
			(layer "F.Fab")
		)
		(fp_line
			(start 0.120396 0.3048)
			(end 0.120396 0.2794)
			(stroke
				(width 0.1)
				(type default)
			)
			(layer "F.Fab")
		)
		(fp_line
			(start -0.12065 0.3048)
			(end -0.67945 0.3048)
			(stroke
				(width 0.1)
				(type default)
			)
			(layer "F.Fab")
		)
		(fp_line
			(start -0.67945 0.3048)
			(end -0.67945 -0.305054)
			(stroke
				(width 0.1)
				(type default)
			)
			(layer "F.Fab")
		)
		(pad "1" smd circle
			(at -0.40005 0 90)
			(size 0 0)
			(layers "F.Cu" "F.Mask" "F.Paste")
			(net "GND")
		)
		(pad "2" smd circle
			(at 0.40005 0 90)
			(size 0 0)
			(layers "F.Cu" "F.Mask" "F.Paste")
			(net "P1V8_PEX")
		)
	)
	(footprint ""
		(layer "F.Cu")
		(at 446.746376 -58.323734)
		(property "Reference" "PC403"
			(at 0 0 0)
			(layer "F.SilkS")
			(hide yes)
			(effects
				(font
					(size 1.27 1.27)
				)
			)
		)
		(property "Value" ""
			(at 0 0 0)
			(layer "F.Fab")
			(effects
				(font
					(size 1.27 1.27)
				)
			)
		)
		(duplicate_pad_numbers_are_jumpers no)
		(fp_line
			(start -1.524 -0.762)
			(end 1.524 -0.762)
			(stroke
				(width 0.1524)
				(type default)
			)
			(layer "F.SilkS")
		)
		(fp_line
			(start -1.524 0.762)
			(end -1.524 -0.762)
			(stroke
				(width 0.1524)
				(type default)
			)
			(layer "F.SilkS")
		)
		(fp_line
			(start 1.524 -0.762)
			(end 1.524 0.762)
			(stroke
				(width 0.1524)
				(type default)
			)
			(layer "F.SilkS")
		)
		(fp_line
			(start 1.524 0.762)
			(end -1.524 0.762)
			(stroke
				(width 0.1524)
				(type default)
			)
			(layer "F.SilkS")
		)
		(fp_line
			(start -1.1049 -0.724916)
			(end -1.1049 0.724916)
			(stroke
				(width 0.1)
				(type default)
			)
			(layer "F.Fab")
		)
		(fp_line
			(start -1.1049 0.724916)
			(end 1.1049 0.724916)
			(stroke
				(width 0.1)
				(type default)
			)
			(layer "F.Fab")
		)
		(fp_line
			(start 1.1049 -0.724916)
			(end -1.1049 -0.724916)
			(stroke
				(width 0.1)
				(type default)
			)
			(layer "F.Fab")
		)
		(fp_line
			(start 1.1049 0.724916)
			(end 1.1049 -0.724916)
			(stroke
				(width 0.1)
				(type default)
			)
			(layer "F.Fab")
		)
		(pad "1" smd rect
			(at -0.889 0 180)
			(size 1.016 1.27)
			(layers "F.Cu" "F.Mask" "F.Paste")
			(net "GND")
		)
		(pad "2" smd rect
			(at 0.889 0 180)
			(size 1.016 1.27)
			(layers "F.Cu" "F.Mask" "F.Paste")
			(net "P12V_AUX")
		)
	)
	(footprint ""
		(layer "F.Cu")
		(at 127.832612 -162.003994 90)
		(property "Reference" "PC635"
			(at 0 0 90)
			(layer "F.SilkS")
			(hide yes)
			(effects
				(font
					(size 1.27 1.27)
				)
			)
		)
		(property "Value" ""
			(at 0 0 90)
			(layer "F.Fab")
			(effects
				(font
					(size 1.27 1.27)
				)
			)
		)
		(duplicate_pad_numbers_are_jumpers no)
		(fp_line
			(start 0.7874 -0.4064)
			(end 0.7874 0.4064)
			(stroke
				(width 0.1524)
				(type default)
			)
			(layer "F.SilkS")
		)
		(fp_line
			(start -0.7874 -0.4064)
			(end 0.7874 -0.4064)
			(stroke
				(width 0.1524)
				(type default)
			)
			(layer "F.SilkS")
		)
		(fp_line
			(start 0.7874 0.4064)
			(end -0.7874 0.4064)
			(stroke
				(width 0.1524)
				(type default)
			)
			(layer "F.SilkS")
		)
		(fp_line
			(start -0.7874 0.4064)
			(end -0.7874 -0.4064)
			(stroke
				(width 0.1524)
				(type default)
			)
			(layer "F.SilkS")
		)
		(fp_line
			(start -0.12065 -0.305054)
			(end -0.12065 -0.2794)
			(stroke
				(width 0.1)
				(type default)
			)
			(layer "F.Fab")
		)
		(fp_line
			(start -0.67945 -0.305054)
			(end -0.12065 -0.305054)
			(stroke
				(width 0.1)
				(type default)
			)
			(layer "F.Fab")
		)
		(fp_line
			(start 0.67945 -0.3048)
			(end 0.67945 0.3048)
			(stroke
				(width 0.1)
				(type default)
			)
			(layer "F.Fab")
		)
		(fp_line
			(start 0.12065 -0.3048)
			(end 0.67945 -0.3048)
			(stroke
				(width 0.1)
				(type default)
			)
			(layer "F.Fab")
		)
		(fp_line
			(start 0.12065 -0.2794)
			(end 0.12065 -0.3048)
			(stroke
				(width 0.1)
				(type default)
			)
			(layer "F.Fab")
		)
		(fp_line
			(start -0.12065 -0.2794)
			(end 0.12065 -0.2794)
			(stroke
				(width 0.1)
				(type default)
			)
			(layer "F.Fab")
		)
		(fp_line
			(start 0.120396 0.2794)
			(end -0.12065 0.2794)
			(stroke
				(width 0.1)
				(type default)
			)
			(layer "F.Fab")
		)
		(fp_line
			(start -0.12065 0.2794)
			(end -0.12065 0.3048)
			(stroke
				(width 0.1)
				(type default)
			)
			(layer "F.Fab")
		)
		(fp_line
			(start 0.67945 0.3048)
			(end 0.120396 0.3048)
			(stroke
				(width 0.1)
				(type default)
			)
			(layer "F.Fab")
		)
		(fp_line
			(start 0.120396 0.3048)
			(end 0.120396 0.2794)
			(stroke
				(width 0.1)
				(type default)
			)
			(layer "F.Fab")
		)
		(fp_line
			(start -0.12065 0.3048)
			(end -0.67945 0.3048)
			(stroke
				(width 0.1)
				(type default)
			)
			(layer "F.Fab")
		)
		(fp_line
			(start -0.67945 0.3048)
			(end -0.67945 -0.305054)
			(stroke
				(width 0.1)
				(type default)
			)
			(layer "F.Fab")
		)
		(pad "1" smd circle
			(at -0.40005 0 90)
			(size 0 0)
			(layers "F.Cu" "F.Mask" "F.Paste")
			(net "P12V_NIC2_CO_ISET_R")
		)
		(pad "2" smd circle
			(at 0.40005 0 90)
			(size 0 0)
			(layers "F.Cu" "F.Mask" "F.Paste")
			(net "GND")
		)
	)
	(footprint ""
		(layer "F.Cu")
		(at 136.225534 -42.849038 180)
		(property "Reference" "R557"
			(at 0 0 180)
			(layer "F.SilkS")
			(hide yes)
			(effects
				(font
					(size 1.27 1.27)
				)
			)
		)
		(property "Value" ""
			(at 0 0 180)
			(layer "F.Fab")
			(effects
				(font
					(size 1.27 1.27)
				)
			)
		)
		(duplicate_pad_numbers_are_jumpers no)
		(fp_line
			(start 0.7874 0.4064)
			(end -0.7874 0.4064)
			(stroke
				(width 0.1524)
				(type default)
			)
			(layer "F.SilkS")
		)
		(fp_line
			(start 0.7874 -0.4064)
			(end 0.7874 0.4064)
			(stroke
				(width 0.1524)
				(type default)
			)
			(layer "F.SilkS")
		)
		(fp_line
			(start -0.7874 0.4064)
			(end -0.7874 -0.4064)
			(stroke
				(width 0.1524)
				(type default)
			)
			(layer "F.SilkS")
		)
		(fp_line
			(start -0.7874 -0.4064)
			(end 0.7874 -0.4064)
			(stroke
				(width 0.1524)
				(type default)
			)
			(layer "F.SilkS")
		)
		(fp_line
			(start 0.67945 0.3048)
			(end 0.120396 0.3048)
			(stroke
				(width 0.1)
				(type default)
			)
			(layer "F.Fab")
		)
		(fp_line
			(start 0.67945 -0.3048)
			(end 0.67945 0.3048)
			(stroke
				(width 0.1)
				(type default)
			)
			(layer "F.Fab")
		)
		(fp_line
			(start 0.12065 -0.2794)
			(end 0.12065 -0.3048)
			(stroke
				(width 0.1)
				(type default)
			)
			(layer "F.Fab")
		)
		(fp_line
			(start 0.12065 -0.3048)
			(end 0.67945 -0.3048)
			(stroke
				(width 0.1)
				(type default)
			)
			(layer "F.Fab")
		)
		(fp_line
			(start 0.120396 0.3048)
			(end 0.120396 0.2794)
			(stroke
				(width 0.1)
				(type default)
			)
			(layer "F.Fab")
		)
		(fp_line
			(start 0.120396 0.2794)
			(end -0.12065 0.2794)
			(stroke
				(width 0.1)
				(type default)
			)
			(layer "F.Fab")
		)
		(fp_line
			(start -0.12065 0.3048)
			(end -0.67945 0.3048)
			(stroke
				(width 0.1)
				(type default)
			)
			(layer "F.Fab")
		)
		(fp_line
			(start -0.12065 0.2794)
			(end -0.12065 0.3048)
			(stroke
				(width 0.1)
				(type default)
			)
			(layer "F.Fab")
		)
		(fp_line
			(start -0.12065 -0.2794)
			(end 0.12065 -0.2794)
			(stroke
				(width 0.1)
				(type default)
			)
			(layer "F.Fab")
		)
		(fp_line
			(start -0.12065 -0.305054)
			(end -0.12065 -0.2794)
			(stroke
				(width 0.1)
				(type default)
			)
			(layer "F.Fab")
		)
		(fp_line
			(start -0.67945 0.3048)
			(end -0.67945 -0.305054)
			(stroke
				(width 0.1)
				(type default)
			)
			(layer "F.Fab")
		)
		(fp_line
			(start -0.67945 -0.305054)
			(end -0.12065 -0.305054)
			(stroke
				(width 0.1)
				(type default)
			)
			(layer "F.Fab")
		)
		(pad "1" smd circle
			(at -0.40005 0 180)
			(size 0 0)
			(layers "F.Cu" "F.Mask" "F.Paste")
			(net "P12V_SSD4_R")
		)
		(pad "2" smd circle
			(at 0.40005 0 180)
			(size 0 0)
			(layers "F.Cu" "F.Mask" "F.Paste")
			(net "P12V_SSD4_VIN_P")
		)
	)
	(footprint ""
		(layer "F.Cu")
		(at 490.25937 -551.726608 180)
		(property "Reference" "SCREW_SSD0_1"
			(at -5.207 -1.402334 0)
			(unlocked yes)
			(layer "B.SilkS")
			(effects
				(font
					(size 0.7874 0.5842)
					(thickness 0.1524)
				)
				(justify mirror)
			)
		)
		(property "Value" ""
			(at 0 0 180)
			(layer "F.Fab")
			(effects
				(font
					(size 1.27 1.27)
				)
			)
		)
		(duplicate_pad_numbers_are_jumpers no)
		(pad "1" thru_hole circle
			(at 0 0 180)
			(size 0.4572 0.4572)
			(drill 0.2032)
			(layers "*.Cu" "*.Mask")
			(remove_unused_layers no)
			(net "Net_9156")
			(clearance 0.127)
			(thermal_gap 0.127)
			(padstack
				(mode front_inner_back)
				(layer "Inner"
					(shape circle)
					(size 0.4572 0.4572)
					(clearance 0.127)
				)
				(layer "B.Cu"
					(shape circle)
					(size 0.508 0.508)
					(clearance 0.1016)
				)
			)
		)
	)
	(footprint ""
		(layer "F.Cu")
		(at 359.85831 -258.131564)
		(property "Reference" "C837"
			(at 0 0 0)
			(layer "F.SilkS")
			(hide yes)
			(effects
				(font
					(size 1.27 1.27)
				)
			)
		)
		(property "Value" ""
			(at 0 0 0)
			(layer "F.Fab")
			(effects
				(font
					(size 1.27 1.27)
				)
			)
		)
		(duplicate_pad_numbers_are_jumpers no)
		(fp_line
			(start -0.7874 -0.4064)
			(end 0.7874 -0.4064)
			(stroke
				(width 0.1524)
				(type default)
			)
			(layer "F.SilkS")
		)
		(fp_line
			(start -0.7874 0.4064)
			(end -0.7874 -0.4064)
			(stroke
				(width 0.1524)
				(type default)
			)
			(layer "F.SilkS")
		)
		(fp_line
			(start 0.7874 -0.4064)
			(end 0.7874 0.4064)
			(stroke
				(width 0.1524)
				(type default)
			)
			(layer "F.SilkS")
		)
		(fp_line
			(start 0.7874 0.4064)
			(end -0.7874 0.4064)
			(stroke
				(width 0.1524)
				(type default)
			)
			(layer "F.SilkS")
		)
		(fp_line
			(start -0.67945 -0.305054)
			(end -0.12065 -0.305054)
			(stroke
				(width 0.1)
				(type default)
			)
			(layer "F.Fab")
		)
		(fp_line
			(start -0.67945 0.3048)
			(end -0.67945 -0.305054)
			(stroke
				(width 0.1)
				(type default)
			)
			(layer "F.Fab")
		)
		(fp_line
			(start -0.12065 -0.305054)
			(end -0.12065 -0.2794)
			(stroke
				(width 0.1)
				(type default)
			)
			(layer "F.Fab")
		)
		(fp_line
			(start -0.12065 -0.2794)
			(end 0.12065 -0.2794)
			(stroke
				(width 0.1)
				(type default)
			)
			(layer "F.Fab")
		)
		(fp_line
			(start -0.12065 0.2794)
			(end -0.12065 0.3048)
			(stroke
				(width 0.1)
				(type default)
			)
			(layer "F.Fab")
		)
		(fp_line
			(start -0.12065 0.3048)
			(end -0.67945 0.3048)
			(stroke
				(width 0.1)
				(type default)
			)
			(layer "F.Fab")
		)
		(fp_line
			(start 0.120396 0.2794)
			(end -0.12065 0.2794)
			(stroke
				(width 0.1)
				(type default)
			)
			(layer "F.Fab")
		)
		(fp_line
			(start 0.120396 0.3048)
			(end 0.120396 0.2794)
			(stroke
				(width 0.1)
				(type default)
			)
			(layer "F.Fab")
		)
		(fp_line
			(start 0.12065 -0.3048)
			(end 0.67945 -0.3048)
			(stroke
				(width 0.1)
				(type default)
			)
			(layer "F.Fab")
		)
		(fp_line
			(start 0.12065 -0.2794)
			(end 0.12065 -0.3048)
			(stroke
				(width 0.1)
				(type default)
			)
			(layer "F.Fab")
		)
		(fp_line
			(start 0.67945 -0.3048)
			(end 0.67945 0.3048)
			(stroke
				(width 0.1)
				(type default)
			)
			(layer "F.Fab")
		)
		(fp_line
			(start 0.67945 0.3048)
			(end 0.120396 0.3048)
			(stroke
				(width 0.1)
				(type default)
			)
			(layer "F.Fab")
		)
		(pad "1" smd circle
			(at -0.40005 0)
			(size 0 0)
			(layers "F.Cu" "F.Mask" "F.Paste")
			(net "P0V8_PEX3_BVRRDY")
		)
		(pad "2" smd circle
			(at 0.40005 0)
			(size 0 0)
			(layers "F.Cu" "F.Mask" "F.Paste")
			(net "GND")
		)
	)
	(footprint ""
		(layer "F.Cu")
		(at 161.346896 -37.47516)
		(property "Reference" "R6074"
			(at 0 0 0)
			(layer "F.SilkS")
			(hide yes)
			(effects
				(font
					(size 1.27 1.27)
				)
			)
		)
		(property "Value" ""
			(at 0 0 0)
			(layer "F.Fab")
			(effects
				(font
					(size 1.27 1.27)
				)
			)
		)
		(duplicate_pad_numbers_are_jumpers no)
		(fp_line
			(start -0.7874 -0.4064)
			(end 0.7874 -0.4064)
			(stroke
				(width 0.1524)
				(type default)
			)
			(layer "F.SilkS")
		)
		(fp_line
			(start -0.7874 0.4064)
			(end -0.7874 -0.4064)
			(stroke
				(width 0.1524)
				(type default)
			)
			(layer "F.SilkS")
		)
		(fp_line
			(start 0.7874 -0.4064)
			(end 0.7874 0.4064)
			(stroke
				(width 0.1524)
				(type default)
			)
			(layer "F.SilkS")
		)
		(fp_line
			(start 0.7874 0.4064)
			(end -0.7874 0.4064)
			(stroke
				(width 0.1524)
				(type default)
			)
			(layer "F.SilkS")
		)
		(fp_line
			(start -0.67945 -0.305054)
			(end -0.12065 -0.305054)
			(stroke
				(width 0.1)
				(type default)
			)
			(layer "F.Fab")
		)
		(fp_line
			(start -0.67945 0.3048)
			(end -0.67945 -0.305054)
			(stroke
				(width 0.1)
				(type default)
			)
			(layer "F.Fab")
		)
		(fp_line
			(start -0.12065 -0.305054)
			(end -0.12065 -0.2794)
			(stroke
				(width 0.1)
				(type default)
			)
			(layer "F.Fab")
		)
		(fp_line
			(start -0.12065 -0.2794)
			(end 0.12065 -0.2794)
			(stroke
				(width 0.1)
				(type default)
			)
			(layer "F.Fab")
		)
		(fp_line
			(start -0.12065 0.2794)
			(end -0.12065 0.3048)
			(stroke
				(width 0.1)
				(type default)
			)
			(layer "F.Fab")
		)
		(fp_line
			(start -0.12065 0.3048)
			(end -0.67945 0.3048)
			(stroke
				(width 0.1)
				(type default)
			)
			(layer "F.Fab")
		)
		(fp_line
			(start 0.120396 0.2794)
			(end -0.12065 0.2794)
			(stroke
				(width 0.1)
				(type default)
			)
			(layer "F.Fab")
		)
		(fp_line
			(start 0.120396 0.3048)
			(end 0.120396 0.2794)
			(stroke
				(width 0.1)
				(type default)
			)
			(layer "F.Fab")
		)
		(fp_line
			(start 0.12065 -0.3048)
			(end 0.67945 -0.3048)
			(stroke
				(width 0.1)
				(type default)
			)
			(layer "F.Fab")
		)
		(fp_line
			(start 0.12065 -0.2794)
			(end 0.12065 -0.3048)
			(stroke
				(width 0.1)
				(type default)
			)
			(layer "F.Fab")
		)
		(fp_line
			(start 0.67945 -0.3048)
			(end 0.67945 0.3048)
			(stroke
				(width 0.1)
				(type default)
			)
			(layer "F.Fab")
		)
		(fp_line
			(start 0.67945 0.3048)
			(end 0.120396 0.3048)
			(stroke
				(width 0.1)
				(type default)
			)
			(layer "F.Fab")
		)
		(pad "1" smd circle
			(at -0.40005 0)
			(size 0 0)
			(layers "F.Cu" "F.Mask" "F.Paste")
			(net "P3V3_SSD6")
		)
		(pad "2" smd circle
			(at 0.40005 0)
			(size 0 0)
			(layers "F.Cu" "F.Mask" "F.Paste")
			(net "P3V3_SSD6_PG_G1")
		)
	)
)
